(kicad_pcb
	(version 20260206)
	(generator "pcbnew")
	(generator_version "10.0")
	(general
		(thickness 1.6)
		(legacy_teardrops no)
	)
	(paper "A4")
	(title_block
		(title "9054_F0T_PDB_BD_GPU_F_V04_1213_1550_OCP.brd")
		(comment 1 "Grand Teton / footprints 581-584 of 608")
	)
	(layers
		(0 "F.Cu" signal "TOP")
		(4 "In1.Cu" signal "GND")
		(6 "In2.Cu" signal "IN1")
		(8 "In3.Cu" signal "GND1")
		(10 "In4.Cu" signal "VCC")
		(12 "In5.Cu" signal "VCC1")
		(14 "In6.Cu" signal "GND2")
		(16 "In7.Cu" signal "IN2")
		(18 "In8.Cu" signal "GND3")
		(2 "B.Cu" signal "BOTTOM")
		(9 "F.Adhes" user "F.Adhesive")
		(11 "B.Adhes" user "B.Adhesive")
		(13 "F.Paste" user "Package Geometry/Pastemask Top")
		(15 "B.Paste" user "Package Geometry/Pastemask Bottom")
		(5 "F.SilkS" user "Ref Des/Silkscreen Top")
		(7 "B.SilkS" user "Ref Des/Silkscreen Bottom")
		(1 "F.Mask" user "Board Geometry/Soldermask Top")
		(3 "B.Mask" user "Board Geometry/Soldermask Bottom")
		(17 "Dwgs.User" user "User.Drawings")
		(19 "Cmts.User" user "User.Comments")
		(21 "Eco1.User" user "User.Eco1")
		(23 "Eco2.User" user "User.Eco2")
		(25 "Edge.Cuts" user "Board Geometry/Outline")
		(27 "Margin" user)
		(31 "F.CrtYd" user "Package Geometry/Place Bound Top")
		(29 "B.CrtYd" user "Package Geometry/Place Bound Bottom")
		(35 "F.Fab" user "Ref Des/Assembly Top")
		(33 "B.Fab" user "Ref Des/Assembly Bottom")
	)
	(footprint ""
		(layer "B.Cu")
		(at 179.6034 -51.562)
		(property "Reference" "C88"
			(at 0 0 0)
			(layer "B.SilkS")
			(hide yes)
			(effects
				(font
					(size 1.27 1.27)
				)
				(justify mirror)
			)
		)
		(property "Value" ""
			(at 0 0 0)
			(layer "B.Fab")
			(effects
				(font
					(size 1.27 1.27)
				)
				(justify mirror)
			)
		)
		(duplicate_pad_numbers_are_jumpers no)
		(fp_line
			(start -1.2954 -0.5842)
			(end -1.2954 0.5842)
			(stroke
				(width 0.1524)
				(type default)
			)
			(layer "B.SilkS")
		)
		(fp_line
			(start -1.2954 0.5842)
			(end 1.2954 0.5842)
			(stroke
				(width 0.1524)
				(type default)
			)
			(layer "B.SilkS")
		)
		(fp_line
			(start 1.2954 -0.5842)
			(end -1.2954 -0.5842)
			(stroke
				(width 0.1524)
				(type default)
			)
			(layer "B.SilkS")
		)
		(fp_line
			(start 1.2954 0.5842)
			(end 1.2954 -0.5842)
			(stroke
				(width 0.1524)
				(type default)
			)
			(layer "B.SilkS")
		)
		(fp_line
			(start -1.1938 -0.4064)
			(end -1.1938 0.4064)
			(stroke
				(width 0.1)
				(type default)
			)
			(layer "B.Fab")
		)
		(fp_line
			(start -1.1938 0.4064)
			(end -0.8636 0.4064)
			(stroke
				(width 0.1)
				(type default)
			)
			(layer "B.Fab")
		)
		(fp_line
			(start -0.8636 -0.4572)
			(end -0.8636 -0.4064)
			(stroke
				(width 0.1)
				(type default)
			)
			(layer "B.Fab")
		)
		(fp_line
			(start -0.8636 -0.4064)
			(end -1.1938 -0.4064)
			(stroke
				(width 0.1)
				(type default)
			)
			(layer "B.Fab")
		)
		(fp_line
			(start -0.8636 0.4064)
			(end -0.8636 0.4572)
			(stroke
				(width 0.1)
				(type default)
			)
			(layer "B.Fab")
		)
		(fp_line
			(start -0.8636 0.4572)
			(end 0.8636 0.4572)
			(stroke
				(width 0.1)
				(type default)
			)
			(layer "B.Fab")
		)
		(fp_line
			(start 0.8636 -0.4572)
			(end -0.8636 -0.4572)
			(stroke
				(width 0.1)
				(type default)
			)
			(layer "B.Fab")
		)
		(fp_line
			(start 0.8636 -0.4064)
			(end 0.8636 -0.4572)
			(stroke
				(width 0.1)
				(type default)
			)
			(layer "B.Fab")
		)
		(fp_line
			(start 0.8636 0.4064)
			(end 1.1938 0.4064)
			(stroke
				(width 0.1)
				(type default)
			)
			(layer "B.Fab")
		)
		(fp_line
			(start 0.8636 0.4572)
			(end 0.8636 0.4064)
			(stroke
				(width 0.1)
				(type default)
			)
			(layer "B.Fab")
		)
		(fp_line
			(start 1.1938 -0.4064)
			(end 0.8636 -0.4064)
			(stroke
				(width 0.1)
				(type default)
			)
			(layer "B.Fab")
		)
		(fp_line
			(start 1.1938 0.4064)
			(end 1.1938 -0.4064)
			(stroke
				(width 0.1)
				(type default)
			)
			(layer "B.Fab")
		)
		(pad "1" smd rect
			(at 0.7366 0 270)
			(size 0.7112 0.8128)
			(layers "B.Cu" "B.Mask" "B.Paste")
			(net "FM_HS2_EN_FUSE")
		)
		(pad "2" smd rect
			(at -0.7366 0 270)
			(size 0.7112 0.8128)
			(layers "B.Cu" "B.Mask" "B.Paste")
			(net "GND")
		)
	)
	(footprint ""
		(layer "B.Cu")
		(at 285.9024 -67.945)
		(property "Reference" "PR213"
			(at 0 0 0)
			(layer "B.SilkS")
			(hide yes)
			(effects
				(font
					(size 1.27 1.27)
				)
				(justify mirror)
			)
		)
		(property "Value" ""
			(at 0 0 0)
			(layer "B.Fab")
			(effects
				(font
					(size 1.27 1.27)
				)
				(justify mirror)
			)
		)
		(duplicate_pad_numbers_are_jumpers no)
		(fp_line
			(start -0.7874 -0.4064)
			(end -0.7874 0.4064)
			(stroke
				(width 0.1524)
				(type default)
			)
			(layer "B.SilkS")
		)
		(fp_line
			(start -0.7874 0.4064)
			(end 0.7874 0.4064)
			(stroke
				(width 0.1524)
				(type default)
			)
			(layer "B.SilkS")
		)
		(fp_line
			(start 0.7874 -0.4064)
			(end -0.7874 -0.4064)
			(stroke
				(width 0.1524)
				(type default)
			)
			(layer "B.SilkS")
		)
		(fp_line
			(start 0.7874 0.4064)
			(end 0.7874 -0.4064)
			(stroke
				(width 0.1524)
				(type default)
			)
			(layer "B.SilkS")
		)
		(fp_line
			(start -0.67945 -0.3048)
			(end -0.67945 0.3048)
			(stroke
				(width 0.1)
				(type default)
			)
			(layer "B.Fab")
		)
		(fp_line
			(start -0.67945 0.3048)
			(end -0.120396 0.3048)
			(stroke
				(width 0.1)
				(type default)
			)
			(layer "B.Fab")
		)
		(fp_line
			(start -0.12065 -0.3048)
			(end -0.67945 -0.3048)
			(stroke
				(width 0.1)
				(type default)
			)
			(layer "B.Fab")
		)
		(fp_line
			(start -0.12065 -0.2794)
			(end -0.12065 -0.3048)
			(stroke
				(width 0.1)
				(type default)
			)
			(layer "B.Fab")
		)
		(fp_line
			(start -0.120396 0.2794)
			(end 0.12065 0.2794)
			(stroke
				(width 0.1)
				(type default)
			)
			(layer "B.Fab")
		)
		(fp_line
			(start -0.120396 0.3048)
			(end -0.120396 0.2794)
			(stroke
				(width 0.1)
				(type default)
			)
			(layer "B.Fab")
		)
		(fp_line
			(start 0.12065 -0.305054)
			(end 0.12065 -0.2794)
			(stroke
				(width 0.1)
				(type default)
			)
			(layer "B.Fab")
		)
		(fp_line
			(start 0.12065 -0.2794)
			(end -0.12065 -0.2794)
			(stroke
				(width 0.1)
				(type default)
			)
			(layer "B.Fab")
		)
		(fp_line
			(start 0.12065 0.2794)
			(end 0.12065 0.3048)
			(stroke
				(width 0.1)
				(type default)
			)
			(layer "B.Fab")
		)
		(fp_line
			(start 0.12065 0.3048)
			(end 0.67945 0.3048)
			(stroke
				(width 0.1)
				(type default)
			)
			(layer "B.Fab")
		)
		(fp_line
			(start 0.67945 -0.305054)
			(end 0.12065 -0.305054)
			(stroke
				(width 0.1)
				(type default)
			)
			(layer "B.Fab")
		)
		(fp_line
			(start 0.67945 0.3048)
			(end 0.67945 -0.305054)
			(stroke
				(width 0.1)
				(type default)
			)
			(layer "B.Fab")
		)
		(pad "1" smd circle
			(at 0.40005 0 180)
			(size 0 0)
			(layers "B.Cu" "B.Mask" "B.Paste")
			(net "P52V_HS1_SIO")
		)
		(pad "2" smd circle
			(at -0.40005 0 180)
			(size 0 0)
			(layers "B.Cu" "B.Mask" "B.Paste")
			(net "GND_FIELD_SIGNAL")
		)
	)
	(footprint ""
		(layer "B.Cu")
		(at 191.1604 -52.832 90)
		(property "Reference" "PD11"
			(at 7.84733 2.5146 0)
			(unlocked yes)
			(layer "B.SilkS")
			(effects
				(font
					(size 0.7874 0.5842)
					(thickness 0.1524)
				)
				(justify left mirror)
			)
		)
		(property "Value" ""
			(at 0 0 90)
			(layer "B.Fab")
			(effects
				(font
					(size 1.27 1.27)
				)
				(justify mirror)
			)
		)
		(duplicate_pad_numbers_are_jumpers no)
		(fp_line
			(start 4.664456 -3.109976)
			(end -4.743704 -3.109976)
			(stroke
				(width 0.1524)
				(type default)
			)
			(layer "B.SilkS")
		)
		(fp_line
			(start -4.183126 -3.109976)
			(end -4.794504 -3.109976)
			(stroke
				(width 0.1524)
				(type default)
			)
			(layer "B.SilkS")
		)
		(fp_line
			(start -4.511802 -3.109976)
			(end -4.207002 -3.109976)
			(stroke
				(width 0.1524)
				(type default)
			)
			(layer "B.SilkS")
		)
		(fp_line
			(start -4.6101 -3.109976)
			(end -4.283202 -3.109976)
			(stroke
				(width 0.1524)
				(type default)
			)
			(layer "B.SilkS")
		)
		(fp_line
			(start -4.695444 -3.109976)
			(end -4.695444 3.109976)
			(stroke
				(width 0.1524)
				(type default)
			)
			(layer "B.SilkS")
		)
		(fp_line
			(start -4.70535 -3.109976)
			(end -4.70535 3.109976)
			(stroke
				(width 0.1524)
				(type default)
			)
			(layer "B.SilkS")
		)
		(fp_line
			(start -4.70535 -3.109976)
			(end -4.70535 3.109976)
			(stroke
				(width 0.1524)
				(type default)
			)
			(layer "B.SilkS")
		)
		(fp_line
			(start -4.70535 -3.109976)
			(end -4.70535 3.109976)
			(stroke
				(width 0.1524)
				(type default)
			)
			(layer "B.SilkS")
		)
		(fp_line
			(start -4.805426 -3.109976)
			(end -4.805426 3.109976)
			(stroke
				(width 0.1524)
				(type default)
			)
			(layer "B.SilkS")
		)
		(fp_line
			(start -4.932426 -3.109976)
			(end -4.932426 3.109976)
			(stroke
				(width 0.1524)
				(type default)
			)
			(layer "B.SilkS")
		)
		(fp_line
			(start -5.008626 -3.109976)
			(end -5.008626 3.109976)
			(stroke
				(width 0.1524)
				(type default)
			)
			(layer "B.SilkS")
		)
		(fp_line
			(start -5.110226 -3.109976)
			(end -5.110226 3.109976)
			(stroke
				(width 0.1524)
				(type default)
			)
			(layer "B.SilkS")
		)
		(fp_line
			(start -5.211826 -3.109976)
			(end -5.211826 3.109976)
			(stroke
				(width 0.1524)
				(type default)
			)
			(layer "B.SilkS")
		)
		(fp_line
			(start -5.262626 -3.109976)
			(end -5.262626 3.109976)
			(stroke
				(width 0.1524)
				(type default)
			)
			(layer "B.SilkS")
		)
		(fp_line
			(start -5.313426 -3.109976)
			(end -5.313426 1.0668)
			(stroke
				(width 0.1524)
				(type default)
			)
			(layer "B.SilkS")
		)
		(fp_line
			(start -5.4102 -3.109976)
			(end -4.783074 -3.109976)
			(stroke
				(width 0.1524)
				(type default)
			)
			(layer "B.SilkS")
		)
		(fp_line
			(start 0.508 -1.016)
			(end -0.762 0)
			(stroke
				(width 0.1524)
				(type default)
			)
			(layer "B.SilkS")
		)
		(fp_line
			(start 1.0668 0)
			(end 0.6096 0)
			(stroke
				(width 0.1524)
				(type default)
			)
			(layer "B.SilkS")
		)
		(fp_line
			(start -0.762 0)
			(end -1.2192 0)
			(stroke
				(width 0.1524)
				(type default)
			)
			(layer "B.SilkS")
		)
		(fp_line
			(start -0.762 0)
			(end 0.508 1.016)
			(stroke
				(width 0.1524)
				(type default)
			)
			(layer "B.SilkS")
		)
		(fp_line
			(start 0.508 1.016)
			(end 0.508 -1.016)
			(stroke
				(width 0.1524)
				(type default)
			)
			(layer "B.SilkS")
		)
		(fp_line
			(start -5.4102 1.0668)
			(end -5.4102 -3.109976)
			(stroke
				(width 0.1524)
				(type default)
			)
			(layer "B.SilkS")
		)
		(fp_line
			(start -0.762 1.27)
			(end -0.762 -1.27)
			(stroke
				(width 0.1524)
				(type default)
			)
			(layer "B.SilkS")
		)
		(fp_line
			(start -5.313426 2.0066)
			(end -5.313426 3.109976)
			(stroke
				(width 0.1524)
				(type default)
			)
			(layer "B.SilkS")
		)
		(fp_line
			(start -4.715002 3.035554)
			(end -4.7117 2.984754)
			(stroke
				(width 0.1524)
				(type default)
			)
			(layer "B.SilkS")
		)
		(fp_line
			(start 4.664456 3.109976)
			(end 4.664456 -3.109976)
			(stroke
				(width 0.1524)
				(type default)
			)
			(layer "B.SilkS")
		)
		(fp_line
			(start -4.156202 3.109976)
			(end -4.183126 3.109976)
			(stroke
				(width 0.1524)
				(type default)
			)
			(layer "B.SilkS")
		)
		(fp_line
			(start -4.743704 3.109976)
			(end -4.6101 3.109976)
			(stroke
				(width 0.1524)
				(type default)
			)
			(layer "B.SilkS")
		)
		(fp_line
			(start -4.743704 3.109976)
			(end -5.4102 3.109976)
			(stroke
				(width 0.1524)
				(type default)
			)
			(layer "B.SilkS")
		)
		(fp_line
			(start -4.769104 3.109976)
			(end 4.664456 3.109976)
			(stroke
				(width 0.1524)
				(type default)
			)
			(layer "B.SilkS")
		)
		(fp_line
			(start -4.794504 3.109976)
			(end -3.554984 3.109976)
			(stroke
				(width 0.1524)
				(type default)
			)
			(layer "B.SilkS")
		)
		(fp_line
			(start -5.4102 3.109976)
			(end -5.4102 2.0066)
			(stroke
				(width 0.1524)
				(type default)
			)
			(layer "B.SilkS")
		)
		(fp_line
			(start 4.065016 -3.109976)
			(end -4.065016 -3.109976)
			(stroke
				(width 0.1)
				(type default)
			)
			(layer "B.Fab")
		)
		(fp_line
			(start -4.065016 -3.109976)
			(end -4.065016 3.109976)
			(stroke
				(width 0.1)
				(type default)
			)
			(layer "B.Fab")
		)
		(fp_line
			(start 4.065016 3.109976)
			(end 4.065016 -3.109976)
			(stroke
				(width 0.1)
				(type default)
			)
			(layer "B.Fab")
		)
		(fp_line
			(start -4.065016 3.109976)
			(end 4.065016 3.109976)
			(stroke
				(width 0.1)
				(type default)
			)
			(layer "B.Fab")
		)
		(fp_text user "-"
			(at -7.493 0.32385 270)
			(unlocked yes)
			(layer "B.SilkS")
			(effects
				(font
					(size 1.905 1.4224)
					(thickness 0.1524)
				)
				(justify left mirror)
			)
		)
		(fp_text user "+"
			(at 5.9944 0.37465 270)
			(unlocked yes)
			(layer "B.SilkS")
			(effects
				(font
					(size 1.905 1.4224)
					(thickness 0.1524)
				)
				(justify left mirror)
			)
		)
		(fp_text user "+"
			(at 4.5974 0.24765 270)
			(unlocked yes)
			(layer "B.Fab")
			(effects
				(font
					(size 1.905 1.4224)
					(thickness 0.1524)
				)
				(justify left mirror)
			)
		)
		(fp_text user "-"
			(at -6.643624 0.40005 270)
			(unlocked yes)
			(layer "B.Fab")
			(effects
				(font
					(size 1.905 1.4224)
					(thickness 0.1524)
				)
				(justify left mirror)
			)
		)
		(pad "A" smd rect
			(at 3.299968 0 90)
			(size 2.413 3.302)
			(layers "B.Cu" "B.Mask" "B.Paste")
			(net "GND")
		)
		(pad "C" smd rect
			(at -3.299968 0 90)
			(size 2.413 3.302)
			(layers "B.Cu" "B.Mask" "B.Paste")
			(net "P52V_2_FUSE_1")
		)
	)
	(footprint ""
		(layer "B.Cu")
		(at 249.047 -52.832 90)
		(property "Reference" "PD9"
			(at 5.334 -2.69367 270)
			(unlocked yes)
			(layer "B.SilkS")
			(effects
				(font
					(size 0.7874 0.5842)
					(thickness 0.1524)
				)
				(justify left mirror)
			)
		)
		(property "Value" ""
			(at 0 0 90)
			(layer "B.Fab")
			(effects
				(font
					(size 1.27 1.27)
				)
				(justify mirror)
			)
		)
		(duplicate_pad_numbers_are_jumpers no)
		(fp_line
			(start 4.664456 -3.109976)
			(end -4.743704 -3.109976)
			(stroke
				(width 0.1524)
				(type default)
			)
			(layer "B.SilkS")
		)
		(fp_line
			(start -4.183126 -3.109976)
			(end -4.794504 -3.109976)
			(stroke
				(width 0.1524)
				(type default)
			)
			(layer "B.SilkS")
		)
		(fp_line
			(start -4.511802 -3.109976)
			(end -4.207002 -3.109976)
			(stroke
				(width 0.1524)
				(type default)
			)
			(layer "B.SilkS")
		)
		(fp_line
			(start -4.6101 -3.109976)
			(end -4.283202 -3.109976)
			(stroke
				(width 0.1524)
				(type default)
			)
			(layer "B.SilkS")
		)
		(fp_line
			(start -4.695444 -3.109976)
			(end -4.695444 3.109976)
			(stroke
				(width 0.1524)
				(type default)
			)
			(layer "B.SilkS")
		)
		(fp_line
			(start -4.70535 -3.109976)
			(end -4.70535 3.109976)
			(stroke
				(width 0.1524)
				(type default)
			)
			(layer "B.SilkS")
		)
		(fp_line
			(start -4.70535 -3.109976)
			(end -4.70535 3.109976)
			(stroke
				(width 0.1524)
				(type default)
			)
			(layer "B.SilkS")
		)
		(fp_line
			(start -4.70535 -3.109976)
			(end -4.70535 3.109976)
			(stroke
				(width 0.1524)
				(type default)
			)
			(layer "B.SilkS")
		)
		(fp_line
			(start -4.805426 -3.109976)
			(end -4.805426 3.109976)
			(stroke
				(width 0.1524)
				(type default)
			)
			(layer "B.SilkS")
		)
		(fp_line
			(start -4.932426 -3.109976)
			(end -4.932426 3.109976)
			(stroke
				(width 0.1524)
				(type default)
			)
			(layer "B.SilkS")
		)
		(fp_line
			(start -5.008626 -3.109976)
			(end -5.008626 3.109976)
			(stroke
				(width 0.1524)
				(type default)
			)
			(layer "B.SilkS")
		)
		(fp_line
			(start -5.110226 -3.109976)
			(end -5.110226 3.109976)
			(stroke
				(width 0.1524)
				(type default)
			)
			(layer "B.SilkS")
		)
		(fp_line
			(start -5.211826 -3.109976)
			(end -5.211826 3.109976)
			(stroke
				(width 0.1524)
				(type default)
			)
			(layer "B.SilkS")
		)
		(fp_line
			(start -5.262626 -3.109976)
			(end -5.262626 3.109976)
			(stroke
				(width 0.1524)
				(type default)
			)
			(layer "B.SilkS")
		)
		(fp_line
			(start -5.313426 -3.109976)
			(end -5.313426 -2.1082)
			(stroke
				(width 0.1524)
				(type default)
			)
			(layer "B.SilkS")
		)
		(fp_line
			(start -5.4102 -3.109976)
			(end -4.783074 -3.109976)
			(stroke
				(width 0.1524)
				(type default)
			)
			(layer "B.SilkS")
		)
		(fp_line
			(start -5.4102 -2.3368)
			(end -5.4102 -3.109976)
			(stroke
				(width 0.1524)
				(type default)
			)
			(layer "B.SilkS")
		)
		(fp_line
			(start 0.508 -1.016)
			(end -0.762 0)
			(stroke
				(width 0.1524)
				(type default)
			)
			(layer "B.SilkS")
		)
		(fp_line
			(start -5.313426 -0.9398)
			(end -5.313426 3.109976)
			(stroke
				(width 0.1524)
				(type default)
			)
			(layer "B.SilkS")
		)
		(fp_line
			(start 1.0668 0)
			(end 0.6096 0)
			(stroke
				(width 0.1524)
				(type default)
			)
			(layer "B.SilkS")
		)
		(fp_line
			(start -0.762 0)
			(end -1.2192 0)
			(stroke
				(width 0.1524)
				(type default)
			)
			(layer "B.SilkS")
		)
		(fp_line
			(start -0.762 0)
			(end 0.508 1.016)
			(stroke
				(width 0.1524)
				(type default)
			)
			(layer "B.SilkS")
		)
		(fp_line
			(start 0.508 1.016)
			(end 0.508 -1.016)
			(stroke
				(width 0.1524)
				(type default)
			)
			(layer "B.SilkS")
		)
		(fp_line
			(start -0.762 1.27)
			(end -0.762 -1.27)
			(stroke
				(width 0.1524)
				(type default)
			)
			(layer "B.SilkS")
		)
		(fp_line
			(start -4.715002 3.035554)
			(end -4.7117 2.984754)
			(stroke
				(width 0.1524)
				(type default)
			)
			(layer "B.SilkS")
		)
		(fp_line
			(start 4.664456 3.109976)
			(end 4.664456 -3.109976)
			(stroke
				(width 0.1524)
				(type default)
			)
			(layer "B.SilkS")
		)
		(fp_line
			(start -4.156202 3.109976)
			(end -4.183126 3.109976)
			(stroke
				(width 0.1524)
				(type default)
			)
			(layer "B.SilkS")
		)
		(fp_line
			(start -4.743704 3.109976)
			(end -4.6101 3.109976)
			(stroke
				(width 0.1524)
				(type default)
			)
			(layer "B.SilkS")
		)
		(fp_line
			(start -4.743704 3.109976)
			(end -5.4102 3.109976)
			(stroke
				(width 0.1524)
				(type default)
			)
			(layer "B.SilkS")
		)
		(fp_line
			(start -4.769104 3.109976)
			(end 4.664456 3.109976)
			(stroke
				(width 0.1524)
				(type default)
			)
			(layer "B.SilkS")
		)
		(fp_line
			(start -4.794504 3.109976)
			(end -3.554984 3.109976)
			(stroke
				(width 0.1524)
				(type default)
			)
			(layer "B.SilkS")
		)
		(fp_line
			(start -5.4102 3.109976)
			(end -5.4102 -0.7366)
			(stroke
				(width 0.1524)
				(type default)
			)
			(layer "B.SilkS")
		)
		(fp_line
			(start 4.065016 -3.109976)
			(end -4.065016 -3.109976)
			(stroke
				(width 0.1)
				(type default)
			)
			(layer "B.Fab")
		)
		(fp_line
			(start -4.065016 -3.109976)
			(end -4.065016 3.109976)
			(stroke
				(width 0.1)
				(type default)
			)
			(layer "B.Fab")
		)
		(fp_line
			(start 4.065016 3.109976)
			(end 4.065016 -3.109976)
			(stroke
				(width 0.1)
				(type default)
			)
			(layer "B.Fab")
		)
		(fp_line
			(start -4.065016 3.109976)
			(end 4.065016 3.109976)
			(stroke
				(width 0.1)
				(type default)
			)
			(layer "B.Fab")
		)
		(fp_text user "+"
			(at 6.1976 0.37465 270)
			(unlocked yes)
			(layer "B.SilkS")
			(effects
				(font
					(size 1.905 1.4224)
					(thickness 0.1524)
				)
				(justify left mirror)
			)
		)
		(fp_text user "-"
			(at -7.405624 0.65405 270)
			(unlocked yes)
			(layer "B.SilkS")
			(effects
				(font
					(size 1.905 1.4224)
					(thickness 0.1524)
				)
				(justify left mirror)
			)
		)
		(fp_text user "+"
			(at 4.5974 0.24765 270)
			(unlocked yes)
			(layer "B.Fab")
			(effects
				(font
					(size 1.905 1.4224)
					(thickness 0.1524)
				)
				(justify left mirror)
			)
		)
		(fp_text user "-"
			(at -6.643624 0.40005 270)
			(unlocked yes)
			(layer "B.Fab")
			(effects
				(font
					(size 1.905 1.4224)
					(thickness 0.1524)
				)
				(justify left mirror)
			)
		)
		(pad "A" smd rect
			(at 3.299968 0 90)
			(size 2.413 3.302)
			(layers "B.Cu" "B.Mask" "B.Paste")
			(net "GND")
		)
		(pad "C" smd rect
			(at -3.299968 0 90)
			(size 2.413 3.302)
			(layers "B.Cu" "B.Mask" "B.Paste")
			(net "P52V_1_FUSE_1")
		)
	)
)
